# Lightning_PDPB_EQL.xlsx — 工作表2 (si-constraints)
| PE_RX1_DR1_n |
| PE_RX1_DR1_p |
| PE_RX2_DR1_n |
| PE_RX2_DR1_p |
| PE_RX3_DR1_n |
| PE_RX3_DR1_p |
| PE_RX4_DR1_n |
| PE_RX4_DR1_p |
| PE_RX1_DR10_p |
| PE_RX1_DR10_n |
| PE_RX2_DR10_p |
| PE_RX2_DR10_n |
| PE_RX3_DR10_p |
| PE_RX3_DR10_n |
| PE_RX4_DR10_p |
| PE_RX4_DR10_n |
| PE_RX1_DR0_n |
| PE_RX1_DR0_p |
| PE_RX2_DR0_n |
| PE_RX2_DR0_p |
| PE_RX3_DR0_n |
| PE_RX3_DR0_p |
| PE_RX4_DR0_n |
| PE_RX4_DR0_p |
| PE_RX1_DR5_p |
| PE_RX1_DR5_n |
| PE_RX2_DR5_p |
| PE_RX2_DR5_n |
| PE_RX3_DR5_p |
| PE_RX3_DR5_n |
| PE_RX4_DR5_p |
| PE_RX4_DR5_n |
| PE_RX3_DR4_n |
| PE_RX3_DR4_p |
| PE_RX4_DR4_n |
| PE_RX4_DR4_p |
| PE_RX1_DR3_n |
| PE_RX1_DR3_p |
| PE_RX2_DR3_n |
| PE_RX2_DR3_p |
| PE_RX3_DR3_n |
| PE_RX3_DR3_p |
| PE_RX4_DR3_n |
| PE_RX4_DR3_p |
| PE_RX1_DR7_n |
| PE_RX1_DR7_p |
| PE_RX2_DR7_n |
| PE_RX2_DR7_p |
| PE_RX3_DR7_n |
| PE_RX3_DR7_p |
| PE_RX4_DR7_n |
| PE_RX4_DR7_p |
| PE_RX1_DR2_n |
| PE_RX1_DR2_p |
| PE_RX2_DR2_n |
| PE_RX2_DR2_p |
| PE_RX3_DR2_n |
| PE_RX3_DR2_p |
| PE_RX4_DR2_n |
| PE_RX4_DR2_p |
| PE_RX1_DR11_n |
| PE_RX1_DR11_p |
| PE_RX2_DR11_n |
| PE_RX2_DR11_p |
| PE_RX3_DR11_n |
| PE_RX3_DR11_p |
| PE_RX4_DR11_n |
| PE_RX4_DR11_p |
| PE_RX1_DR6_n |
| PE_RX1_DR6_p |
| PE_RX2_DR6_n |
| PE_RX2_DR6_p |
| PE_RX3_DR6_n |
| PE_RX3_DR6_p |
| PE_RX4_DR6_n |
| PE_RX4_DR6_p |
| PE_RX1_DR14_n |
| PE_RX1_DR14_p |
| PE_RX2_DR14_n |
| PE_RX2_DR14_p |
| PE_RX3_DR14_n |
| PE_RX3_DR14_p |
| PE_RX4_DR14_n |
| PE_RX4_DR14_p |
| PE_RX1_DR13_n |
| PE_RX1_DR13_p |
| PE_RX2_DR13_n |
| PE_RX2_DR13_p |
| PE_RX3_DR13_n |
| PE_RX3_DR13_p |
| PE_RX4_DR13_n |
| PE_RX4_DR13_p |
| PE_RX1_DR9_n |
| PE_RX1_DR9_p |
| PE_RX2_DR9_n |
| PE_RX2_DR9_p |
| PE_RX3_DR9_n |
| PE_RX3_DR9_p |
| PE_RX4_DR9_n |
| PE_RX4_DR9_p |
| PE_RX1_DR8_n |
| PE_RX1_DR8_p |
| PE_RX2_DR8_n |
| PE_RX2_DR8_p |
| PE_RX3_DR8_n |
| PE_RX3_DR8_p |
| PE_RX4_DR8_n |
| PE_RX4_DR8_p |
| PE_RX1_DR12_n |
| PE_RX1_DR12_p |
| PE_RX2_DR12_n |
| PE_RX2_DR12_p |
| PE_RX3_DR12_n |
| PE_RX3_DR12_p |
| PE_RX4_DR12_n |
| PE_RX4_DR12_p |
| PE_RX1_DR4_n |
| PE_RX1_DR4_p |
| PE_RX2_DR4_n |
| PE_RX2_DR4_p |
